FILE_TYPE=LIBRARY_PARTS ;
PRIMITIVE 'Q_RES';
 PIN
  'A':
   PIN_GROUP='1';
   PIN_NUMBER='(1)';
   PIN_TYPE='UNSPEC';
  'B':
   PIN_GROUP='1';
   PIN_NUMBER='(2)';
   PIN_TYPE='UNSPEC';
 END_PIN;
 BODY
  PART_NAME='Q_RES';
  PHYS_DES_PREFIX='R';
 END_BODY;
END_PRIMITIVE;
END.
